# BASEBOARD_FAB2 (Tioga Pass) — schematic netlist excerpt (pin names and nets, part order shuffled) for the footprints in the layout excerpt that follows; sources: Cadence DE-HDL packaged netlist, KiCad conversion of Wiwynn_Tioga_Pass_MB.brd

XLU1  SOCKET_P_MECH_A  PLASTIC  pkg LEFT  page 21

(kicad_pcb
	(version 20260206)
	(generator "pcbnew")
	(generator_version "10.0")
	(general
		(thickness 1.6)
		(legacy_teardrops no)
	)
	(paper "A4")
	(title_block
		(title "Wiwynn_Tioga_Pass_MB.brd")
		(comment 1 "Tioga Pass / footprints 1883-1883 of 4770")
	)
	(layers
		(0 "F.Cu" signal "TOP")
		(4 "In1.Cu" signal "L2GND")
		(6 "In2.Cu" signal "L3")
		(8 "In3.Cu" signal "L4GND")
		(10 "In4.Cu" signal "L5")
		(12 "In5.Cu" signal "L6GND")
		(14 "In6.Cu" signal "L7VCC")
		(16 "In7.Cu" signal "L8VCC")
		(18 "In8.Cu" signal "L9GND")
		(20 "In9.Cu" signal "L10")
		(22 "In10.Cu" signal "L11GND")
		(24 "In11.Cu" signal "L12")
		(26 "In12.Cu" signal "L13GND")
		(2 "B.Cu" signal "BOTTOM")
		(9 "F.Adhes" user "F.Adhesive")
		(11 "B.Adhes" user "B.Adhesive")
		(13 "F.Paste" user "Package Geometry/Pastemask Top")
		(15 "B.Paste" user "Package Geometry/Pastemask Bottom")
		(5 "F.SilkS" user "Ref Des/Silkscreen Top")
		(7 "B.SilkS" user "Ref Des/Silkscreen Bottom")
		(1 "F.Mask" user "Board Geometry/Soldermask Top")
		(3 "B.Mask" user "Board Geometry/Soldermask Bottom")
		(17 "Dwgs.User" user "User.Drawings")
		(19 "Cmts.User" user "User.Comments")
		(21 "Eco1.User" user "User.Eco1")
		(23 "Eco2.User" user "User.Eco2")
		(25 "Edge.Cuts" user "Board Geometry/Outline")
		(27 "Margin" user)
		(31 "F.CrtYd" user "Package Geometry/Place Bound Top")
		(29 "B.CrtYd" user "Package Geometry/Place Bound Bottom")
		(35 "F.Fab" user "Ref Des/Assembly Top")
		(33 "B.Fab" user "Ref Des/Assembly Bottom")
	)
	(footprint ""
		(layer "F.Cu")
		(at 250.77801 -75.65009 180)
		(property "Reference" "XLU1"
			(at 19.38401 33.79724 0)
			(unlocked yes)
			(layer "F.SilkS")
			(effects
				(font
					(size 0.7874 0.5842)
					(thickness 0.1524)
				)
				(justify left)
			)
		)
		(property "Value" ""
			(at 0 0 180)
			(layer "F.Fab")
			(effects
				(font
					(size 1.27 1.27)
				)
			)
		)
		(duplicate_pad_numbers_are_jumpers no)
		(fp_line
			(start 21.77796 31.949898)
			(end 21.77796 8.899906)
			(stroke
				(width 0.1524)
				(type default)
			)
			(layer "F.SilkS")
		)
		(fp_line
			(start 21.77796 8.899906)
			(end 18.278094 5.40004)
			(stroke
				(width 0.1524)
				(type default)
			)
			(layer "F.SilkS")
		)
		(fp_line
			(start 21.77796 -7.100062)
			(end 21.77796 -30.150054)
			(stroke
				(width 0.1524)
				(type default)
			)
			(layer "F.SilkS")
		)
		(fp_line
			(start 21.77796 -30.150054)
			(end 14.777974 -30.150054)
			(stroke
				(width 0.1524)
				(type default)
			)
			(layer "F.SilkS")
		)
		(fp_line
			(start 18.278094 5.40004)
			(end 18.278094 3.899916)
			(stroke
				(width 0.1524)
				(type default)
			)
			(layer "F.SilkS")
		)
		(fp_line
			(start 18.278094 3.899916)
			(end 17.777968 3.899916)
			(stroke
				(width 0.1524)
				(type default)
			)
			(layer "F.SilkS")
		)
		(fp_line
			(start 18.278094 -2.100072)
			(end 18.278094 -3.599942)
			(stroke
				(width 0.1524)
				(type default)
			)
			(layer "F.SilkS")
		)
		(fp_line
			(start 18.278094 -3.599942)
			(end 21.77796 -7.100062)
			(stroke
				(width 0.1524)
				(type default)
			)
			(layer "F.SilkS")
		)
		(fp_line
			(start 17.777968 3.899916)
			(end 17.777968 -2.100072)
			(stroke
				(width 0.1524)
				(type default)
			)
			(layer "F.SilkS")
		)
		(fp_line
			(start 17.777968 -2.100072)
			(end 18.278094 -2.100072)
			(stroke
				(width 0.1524)
				(type default)
			)
			(layer "F.SilkS")
		)
		(fp_line
			(start 14.777974 31.949898)
			(end 21.77796 31.949898)
			(stroke
				(width 0.1524)
				(type default)
			)
			(layer "F.SilkS")
		)
		(fp_line
			(start 14.777974 29.399992)
			(end 14.777974 31.949898)
			(stroke
				(width 0.1524)
				(type default)
			)
			(layer "F.SilkS")
		)
		(fp_line
			(start 14.777974 -27.599894)
			(end -17.622012 -27.599894)
			(stroke
				(width 0.1524)
				(type default)
			)
			(layer "F.SilkS")
		)
		(fp_line
			(start 14.777974 -30.150054)
			(end 14.777974 -27.599894)
			(stroke
				(width 0.1524)
				(type default)
			)
			(layer "F.SilkS")
		)
		(fp_line
			(start -6.171946 6.690106)
			(end -12.761976 10.649966)
			(stroke
				(width 0.1524)
				(type default)
			)
			(layer "F.SilkS")
		)
		(fp_line
			(start -6.171946 -4.890008)
			(end -6.171946 6.690106)
			(stroke
				(width 0.1524)
				(type default)
			)
			(layer "F.SilkS")
		)
		(fp_line
			(start -12.761976 10.649966)
			(end -19.221958 10.649966)
			(stroke
				(width 0.1524)
				(type default)
			)
			(layer "F.SilkS")
		)
		(fp_line
			(start -12.761976 -8.850122)
			(end -6.171946 -4.890008)
			(stroke
				(width 0.1524)
				(type default)
			)
			(layer "F.SilkS")
		)
		(fp_line
			(start -17.622012 30.39999)
			(end -17.622012 29.399992)
			(stroke
				(width 0.1524)
				(type default)
			)
			(layer "F.SilkS")
		)
		(fp_line
			(start -17.622012 29.399992)
			(end 14.777974 29.399992)
			(stroke
				(width 0.1524)
				(type default)
			)
			(layer "F.SilkS")
		)
		(fp_line
			(start -17.622012 -27.599894)
			(end -17.622012 -28.599892)
			(stroke
				(width 0.1524)
				(type default)
			)
			(layer "F.SilkS")
		)
		(fp_line
			(start -17.622012 -28.599892)
			(end -18.62201 -28.599892)
			(stroke
				(width 0.1524)
				(type default)
			)
			(layer "F.SilkS")
		)
		(fp_line
			(start -18.62201 30.39999)
			(end -17.622012 30.39999)
			(stroke
				(width 0.1524)
				(type default)
			)
			(layer "F.SilkS")
		)
		(fp_line
			(start -18.62201 29.399992)
			(end -18.62201 30.39999)
			(stroke
				(width 0.1524)
				(type default)
			)
			(layer "F.SilkS")
		)
		(fp_line
			(start -18.62201 -8.850122)
			(end -12.761976 -8.850122)
			(stroke
				(width 0.1524)
				(type default)
			)
			(layer "F.SilkS")
		)
		(fp_line
			(start -18.62201 -28.599892)
			(end -18.62201 -8.850122)
			(stroke
				(width 0.1524)
				(type default)
			)
			(layer "F.SilkS")
		)
		(fp_line
			(start -19.221958 29.399992)
			(end -18.62201 29.399992)
			(stroke
				(width 0.1524)
				(type default)
			)
			(layer "F.SilkS")
		)
		(fp_line
			(start -19.221958 10.649966)
			(end -19.221958 29.399992)
			(stroke
				(width 0.1524)
				(type default)
			)
			(layer "F.SilkS")
		)
		(fp_poly
			(pts
				(xy 19.777964 -5.100066) (xy 19.777964 -22.649942) (xy 18.839434 -22.649942) (xy 18.839434 -27.410918)
				(xy 14.777974 -27.410918) (xy 14.777974 -30.150054) (xy 21.77796 -30.150054) (xy 21.77796 -7.100062)
			)
			(stroke
				(width 0)
				(type default)
			)
			(fill no)
			(layer "F.CrtYd")
		)
		(fp_poly
			(pts
				(arc
					(start 19.777964 17.616678)
					(mid 20.051978 16.900049)
					(end 19.777964 16.183356)
				)
				(xy 19.777964 6.89991) (xy 21.77796 8.899906) (xy 21.77796 31.949898) (xy 14.777974 31.949898) (xy 14.777974 29.211016)
				(xy 18.839434 29.211016) (xy 18.839434 24.449786) (xy 19.777964 24.449786)
			)
			(stroke
				(width 0)
				(type default)
			)
			(fill no)
			(layer "F.CrtYd")
		)
		(fp_line
			(start 21.77796 31.949898)
			(end 14.777974 31.949898)
			(stroke
				(width 0.1)
				(type default)
			)
			(layer "F.Fab")
		)
		(fp_line
			(start 21.77796 8.899906)
			(end 21.77796 31.949898)
			(stroke
				(width 0.1)
				(type default)
			)
			(layer "F.Fab")
		)
		(fp_line
			(start 21.77796 -7.100062)
			(end 19.777964 -5.100066)
			(stroke
				(width 0.1)
				(type default)
			)
			(layer "F.Fab")
		)
		(fp_line
			(start 21.77796 -30.150054)
			(end 21.77796 -7.100062)
			(stroke
				(width 0.1)
				(type default)
			)
			(layer "F.Fab")
		)
		(fp_line
			(start 19.777964 24.449786)
			(end 19.777964 22.078696)
			(stroke
				(width 0.1)
				(type default)
			)
			(layer "F.Fab")
		)
		(fp_line
			(start 19.777964 21.179028)
			(end 19.777964 17.616678)
			(stroke
				(width 0.1)
				(type default)
			)
			(layer "F.Fab")
		)
		(fp_line
			(start 19.777964 16.183356)
			(end 19.777964 6.89991)
			(stroke
				(width 0.1)
				(type default)
			)
			(layer "F.Fab")
		)
		(fp_line
			(start 19.777964 6.89991)
			(end 21.77796 8.899906)
			(stroke
				(width 0.1)
				(type default)
			)
			(layer "F.Fab")
		)
		(fp_line
			(start 19.777964 -5.100066)
			(end 19.777964 -22.649942)
			(stroke
				(width 0.1)
				(type default)
			)
			(layer "F.Fab")
		)
		(fp_line
			(start 19.777964 -22.649942)
			(end 18.839434 -22.649942)
			(stroke
				(width 0.1)
				(type default)
			)
			(layer "F.Fab")
		)
		(fp_line
			(start 18.839434 29.211016)
			(end 18.839434 24.449786)
			(stroke
				(width 0.1)
				(type default)
			)
			(layer "F.Fab")
		)
		(fp_line
			(start 18.839434 24.449786)
			(end 19.777964 24.449786)
			(stroke
				(width 0.1)
				(type default)
			)
			(layer "F.Fab")
		)
		(fp_line
			(start 18.839434 -22.649942)
			(end 18.839434 -27.410918)
			(stroke
				(width 0.1)
				(type default)
			)
			(layer "F.Fab")
		)
		(fp_line
			(start 18.839434 -27.410918)
			(end 14.777974 -27.410918)
			(stroke
				(width 0.1)
				(type default)
			)
			(layer "F.Fab")
		)
		(fp_line
			(start 14.777974 31.949898)
			(end 14.777974 29.211016)
			(stroke
				(width 0.1)
				(type default)
			)
			(layer "F.Fab")
		)
		(fp_line
			(start 14.777974 29.211016)
			(end 18.839434 29.211016)
			(stroke
				(width 0.1)
				(type default)
			)
			(layer "F.Fab")
		)
		(fp_line
			(start 14.777974 -27.410918)
			(end 14.777974 -30.150054)
			(stroke
				(width 0.1)
				(type default)
			)
			(layer "F.Fab")
		)
		(fp_line
			(start 14.777974 -30.150054)
			(end 21.77796 -30.150054)
			(stroke
				(width 0.1)
				(type default)
			)
			(layer "F.Fab")
		)
		(fp_arc
			(start 19.777964 22.078696)
			(mid 19.777668 21.628862)
			(end 19.777964 21.179028)
			(stroke
				(width 0.1)
				(type default)
			)
			(layer "F.Fab")
		)
		(fp_arc
			(start 19.777964 16.183356)
			(mid 20.051979 16.900015)
			(end 19.777964 17.616678)
			(stroke
				(width 0.1)
				(type default)
			)
			(layer "F.Fab")
		)
	)
)
